(kicad_pcb
	(version 20260206)
	(generator "pcbnew")
	(generator_version "10.0")
	(general
		(thickness 1.6)
		(legacy_teardrops no)
	)
	(paper "A4")
	(title_block
		(title "04192023_DAF0TMB3IC0_F0TG_MB_C_brd_V02_OCP.brd")
		(comment 1 "Grand Teton / footprints 4512-4516 of 8354")
	)
	(layers
		(0 "F.Cu" signal "TOP")
		(4 "In1.Cu" signal "GND")
		(6 "In2.Cu" signal "IN1")
		(8 "In3.Cu" signal "GND1")
		(10 "In4.Cu" signal "IN2")
		(12 "In5.Cu" signal "GND2")
		(14 "In6.Cu" signal "IN3")
		(16 "In7.Cu" signal "GND3")
		(18 "In8.Cu" signal "VCC")
		(20 "In9.Cu" signal "VCC1")
		(22 "In10.Cu" signal "GND4")
		(24 "In11.Cu" signal "IN4")
		(26 "In12.Cu" signal "GND5")
		(28 "In13.Cu" signal "IN5")
		(30 "In14.Cu" signal "GND6")
		(32 "In15.Cu" signal "IN6")
		(34 "In16.Cu" signal "GND7")
		(2 "B.Cu" signal "BOTTOM")
		(9 "F.Adhes" user "F.Adhesive")
		(11 "B.Adhes" user "B.Adhesive")
		(13 "F.Paste" user "Package Geometry/Pastemask Top")
		(15 "B.Paste" user "Package Geometry/Pastemask Bottom")
		(5 "F.SilkS" user "Ref Des/Silkscreen Top")
		(7 "B.SilkS" user "Ref Des/Silkscreen Bottom")
		(1 "F.Mask" user "Board Geometry/Soldermask Top")
		(3 "B.Mask" user "Board Geometry/Soldermask Bottom")
		(17 "Dwgs.User" user "User.Drawings")
		(19 "Cmts.User" user "User.Comments")
		(21 "Eco1.User" user "User.Eco1")
		(23 "Eco2.User" user "User.Eco2")
		(25 "Edge.Cuts" user "Board Geometry/Outline")
		(27 "Margin" user)
		(31 "F.CrtYd" user "Package Geometry/Place Bound Top")
		(29 "B.CrtYd" user "Package Geometry/Place Bound Bottom")
		(35 "F.Fab" user "Ref Des/Assembly Top")
		(33 "B.Fab" user "Ref Des/Assembly Bottom")
	)
	(footprint ""
		(layer "F.Cu")
		(at 115.275868 -256.012442 90)
		(property "Reference" "C2434"
			(at 0 0 90)
			(layer "F.SilkS")
			(hide yes)
			(effects
				(font
					(size 1.27 1.27)
				)
			)
		)
		(property "Value" ""
			(at 0 0 90)
			(layer "F.Fab")
			(effects
				(font
					(size 1.27 1.27)
				)
			)
		)
		(duplicate_pad_numbers_are_jumpers no)
		(fp_line
			(start 0.7874 -0.4064)
			(end 0.7874 0.4064)
			(stroke
				(width 0.1524)
				(type default)
			)
			(layer "F.SilkS")
		)
		(fp_line
			(start -0.7874 -0.4064)
			(end 0.7874 -0.4064)
			(stroke
				(width 0.1524)
				(type default)
			)
			(layer "F.SilkS")
		)
		(fp_line
			(start 0.7874 0.4064)
			(end -0.7874 0.4064)
			(stroke
				(width 0.1524)
				(type default)
			)
			(layer "F.SilkS")
		)
		(fp_line
			(start -0.7874 0.4064)
			(end -0.7874 -0.4064)
			(stroke
				(width 0.1524)
				(type default)
			)
			(layer "F.SilkS")
		)
		(fp_line
			(start -0.12065 -0.305054)
			(end -0.12065 -0.2794)
			(stroke
				(width 0.1)
				(type default)
			)
			(layer "F.Fab")
		)
		(fp_line
			(start -0.67945 -0.305054)
			(end -0.12065 -0.305054)
			(stroke
				(width 0.1)
				(type default)
			)
			(layer "F.Fab")
		)
		(fp_line
			(start 0.67945 -0.3048)
			(end 0.67945 0.3048)
			(stroke
				(width 0.1)
				(type default)
			)
			(layer "F.Fab")
		)
		(fp_line
			(start 0.12065 -0.3048)
			(end 0.67945 -0.3048)
			(stroke
				(width 0.1)
				(type default)
			)
			(layer "F.Fab")
		)
		(fp_line
			(start 0.12065 -0.2794)
			(end 0.12065 -0.3048)
			(stroke
				(width 0.1)
				(type default)
			)
			(layer "F.Fab")
		)
		(fp_line
			(start -0.12065 -0.2794)
			(end 0.12065 -0.2794)
			(stroke
				(width 0.1)
				(type default)
			)
			(layer "F.Fab")
		)
		(fp_line
			(start 0.120396 0.2794)
			(end -0.12065 0.2794)
			(stroke
				(width 0.1)
				(type default)
			)
			(layer "F.Fab")
		)
		(fp_line
			(start -0.12065 0.2794)
			(end -0.12065 0.3048)
			(stroke
				(width 0.1)
				(type default)
			)
			(layer "F.Fab")
		)
		(fp_line
			(start 0.67945 0.3048)
			(end 0.120396 0.3048)
			(stroke
				(width 0.1)
				(type default)
			)
			(layer "F.Fab")
		)
		(fp_line
			(start 0.120396 0.3048)
			(end 0.120396 0.2794)
			(stroke
				(width 0.1)
				(type default)
			)
			(layer "F.Fab")
		)
		(fp_line
			(start -0.12065 0.3048)
			(end -0.67945 0.3048)
			(stroke
				(width 0.1)
				(type default)
			)
			(layer "F.Fab")
		)
		(fp_line
			(start -0.67945 0.3048)
			(end -0.67945 -0.305054)
			(stroke
				(width 0.1)
				(type default)
			)
			(layer "F.Fab")
		)
		(pad "1" smd circle
			(at -0.40005 0 90)
			(size 0 0)
			(layers "F.Cu" "F.Mask" "F.Paste")
			(net "PVDDCR_SOC_P1")
		)
		(pad "2" smd circle
			(at 0.40005 0 90)
			(size 0 0)
			(layers "F.Cu" "F.Mask" "F.Paste")
			(net "GND")
		)
	)
	(footprint ""
		(layer "F.Cu")
		(at 458.661008 -411.8737)
		(property "Reference" "PC6810"
			(at -1.969008 -3.64363 0)
			(unlocked yes)
			(layer "F.SilkS")
			(effects
				(font
					(size 0.7874 0.5842)
					(thickness 0.1524)
				)
				(justify left)
			)
		)
		(property "Value" ""
			(at 0 0 0)
			(layer "F.Fab")
			(effects
				(font
					(size 1.27 1.27)
				)
			)
		)
		(duplicate_pad_numbers_are_jumpers no)
		(fp_line
			(start -2.750058 -1.988058)
			(end -2.750058 -0.9398)
			(stroke
				(width 0.1524)
				(type default)
			)
			(layer "F.SilkS")
		)
		(fp_line
			(start -2.750058 0.9398)
			(end -2.750058 1.988058)
			(stroke
				(width 0.1524)
				(type default)
			)
			(layer "F.SilkS")
		)
		(fp_line
			(start -2.750058 1.988058)
			(end -1.988058 2.750058)
			(stroke
				(width 0.1524)
				(type default)
			)
			(layer "F.SilkS")
		)
		(fp_line
			(start -1.988058 -2.750058)
			(end -2.750058 -1.988058)
			(stroke
				(width 0.1524)
				(type default)
			)
			(layer "F.SilkS")
		)
		(fp_line
			(start -1.988058 2.750058)
			(end 2.750058 2.750058)
			(stroke
				(width 0.1524)
				(type default)
			)
			(layer "F.SilkS")
		)
		(fp_line
			(start 2.750058 -2.750058)
			(end -1.988058 -2.750058)
			(stroke
				(width 0.1524)
				(type default)
			)
			(layer "F.SilkS")
		)
		(fp_line
			(start 2.750058 -0.9398)
			(end 2.750058 -2.750058)
			(stroke
				(width 0.1524)
				(type default)
			)
			(layer "F.SilkS")
		)
		(fp_line
			(start 2.750058 2.750058)
			(end 2.750058 0.9398)
			(stroke
				(width 0.1524)
				(type default)
			)
			(layer "F.SilkS")
		)
		(fp_line
			(start -2.750058 -2.750058)
			(end -2.750058 2.750058)
			(stroke
				(width 0.1)
				(type default)
			)
			(layer "F.Fab")
		)
		(fp_line
			(start -2.750058 2.750058)
			(end 2.750058 2.750058)
			(stroke
				(width 0.1)
				(type default)
			)
			(layer "F.Fab")
		)
		(fp_line
			(start 2.750058 -2.750058)
			(end -2.750058 -2.750058)
			(stroke
				(width 0.1)
				(type default)
			)
			(layer "F.Fab")
		)
		(fp_line
			(start 2.750058 2.750058)
			(end 2.750058 -2.750058)
			(stroke
				(width 0.1)
				(type default)
			)
			(layer "F.Fab")
		)
		(pad "1" smd rect
			(at -2.199894 0 90)
			(size 1.6002 3.0226)
			(layers "F.Cu" "F.Mask" "F.Paste")
			(net "SW_P12V_AUX_P0V9_RETIMER_CPU0_FLT")
		)
		(pad "2" smd rect
			(at 2.199894 0 90)
			(size 1.6002 3.0226)
			(layers "F.Cu" "F.Mask" "F.Paste")
			(net "GND")
		)
	)
	(footprint ""
		(layer "F.Cu")
		(at 445.131952 -397.245332)
		(property "Reference" "PU6503"
			(at -3.99415 -7.331456 0)
			(unlocked yes)
			(layer "F.SilkS")
			(effects
				(font
					(size 0.7874 0.5842)
					(thickness 0.1524)
				)
				(justify left)
			)
		)
		(property "Value" ""
			(at 0 0 0)
			(layer "F.Fab")
			(effects
				(font
					(size 1.27 1.27)
				)
			)
		)
		(duplicate_pad_numbers_are_jumpers no)
		(fp_line
			(start -2.500122 -2.999994)
			(end -2.24409 -2.999994)
			(stroke
				(width 0.1524)
				(type default)
			)
			(layer "F.SilkS")
		)
		(fp_line
			(start -2.500122 -2.529078)
			(end -2.500122 -2.999994)
			(stroke
				(width 0.1524)
				(type default)
			)
			(layer "F.SilkS")
		)
		(fp_line
			(start -2.500122 0.6604)
			(end -2.500122 0.229108)
			(stroke
				(width 0.1524)
				(type default)
			)
			(layer "F.SilkS")
		)
		(fp_line
			(start -2.500122 2.999994)
			(end -2.500122 2.339594)
			(stroke
				(width 0.1524)
				(type default)
			)
			(layer "F.SilkS")
		)
		(fp_line
			(start -2.2987 2.999994)
			(end -2.500122 2.999994)
			(stroke
				(width 0.1524)
				(type default)
			)
			(layer "F.SilkS")
		)
		(fp_line
			(start 2.31394 -2.999994)
			(end 2.500122 -2.999994)
			(stroke
				(width 0.1524)
				(type default)
			)
			(layer "F.SilkS")
		)
		(fp_line
			(start 2.500122 -2.999994)
			(end 2.500122 -2.44348)
			(stroke
				(width 0.1524)
				(type default)
			)
			(layer "F.SilkS")
		)
		(fp_line
			(start 2.500122 2.339594)
			(end 2.500122 2.999994)
			(stroke
				(width 0.1524)
				(type default)
			)
			(layer "F.SilkS")
		)
		(fp_line
			(start 2.500122 2.999994)
			(end 2.2987 2.999994)
			(stroke
				(width 0.1524)
				(type default)
			)
			(layer "F.SilkS")
		)
		(fp_poly
			(pts
				(xy -3.052318 -3.555746) (xy -3.770884 -2.83718) (xy -2.693162 -2.478024)
			)
			(stroke
				(width 0)
				(type default)
			)
			(fill yes)
			(layer "F.SilkS")
		)
		(fp_line
			(start -2.500122 -2.999994)
			(end 2.500122 -2.999994)
			(stroke
				(width 0.1)
				(type default)
			)
			(layer "F.Fab")
		)
		(fp_line
			(start -2.500122 2.999994)
			(end -2.500122 -2.999994)
			(stroke
				(width 0.1)
				(type default)
			)
			(layer "F.Fab")
		)
		(fp_line
			(start 2.500122 -2.999994)
			(end 2.500122 2.999994)
			(stroke
				(width 0.1)
				(type default)
			)
			(layer "F.Fab")
		)
		(fp_line
			(start 2.500122 2.999994)
			(end -2.500122 2.999994)
			(stroke
				(width 0.1)
				(type default)
			)
			(layer "F.Fab")
		)
		(fp_poly
			(pts
				(xy -4.218432 -2.783078) (xy -4.218432 -1.767078) (xy -3.202432 -2.275078)
			)
			(stroke
				(width 0)
				(type default)
			)
			(fill yes)
			(layer "F.Fab")
		)
		(pad "1" smd rect
			(at -2.400046 -2.275078 90)
			(size 0.2286 0.6096)
			(layers "F.Cu" "F.Mask" "F.Paste")
			(net "P0V9_RETIMER_CPU0_VOS1")
		)
		(pad "2" smd rect
			(at -2.400046 -1.82499 90)
			(size 0.2286 0.6096)
			(layers "F.Cu" "F.Mask" "F.Paste")
			(net "GND")
		)
		(pad "3" smd rect
			(at -2.400046 -1.374902 90)
			(size 0.2286 0.6096)
			(layers "F.Cu" "F.Mask" "F.Paste")
			(net "P0V9_RETIMER_CPU0_VCC1")
		)
		(pad "4" smd rect
			(at -2.400046 -0.925068 90)
			(size 0.2286 0.6096)
			(layers "F.Cu" "F.Mask" "F.Paste")
			(net "P0V9_RETIMER_CPU0_PVCC")
		)
		(pad "5" smd rect
			(at -2.400046 -0.47498 90)
			(size 0.2286 0.6096)
			(layers "F.Cu" "F.Mask" "F.Paste")
			(net "GND")
		)
		(pad "6" smd rect
			(at -2.400046 -0.024892 90)
			(size 0.2286 0.6096)
			(layers "F.Cu" "F.Mask" "F.Paste")
			(net "NC_PV09_RETIMER_CPU0_GL1_1")
		)
		(pad "7_9-20_24" smd circle
			(at 0 1.150112 90)
			(size 0 0)
			(layers "F.Cu" "F.Mask" "F.Paste")
			(net "GND")
		)
		(pad "10_19" smd rect
			(at 0 2.899918 90)
			(size 0.6096 4.318)
			(layers "F.Cu" "F.Mask" "F.Paste")
			(net "SW_P0V9_RETIMER_CPU0_SW1")
		)
		(pad "25_29" smd rect
			(at 1.549908 -1.279906 270)
			(size 2.0574 2.3114)
			(layers "F.Cu" "F.Mask" "F.Paste")
			(net "SW_P12V_AUX_P0V9_RETIMER_CPU0_FLT")
		)
		(pad "30" smd rect
			(at 2.05994 -2.899918)
			(size 0.2286 0.6096)
			(layers "F.Cu" "F.Mask" "F.Paste")
			(net "SW_P12V_AUX_P0V9_RETIMER_CPU0_FLT")
		)
		(pad "31" smd rect
			(at 1.610106 -2.899918)
			(size 0.2286 0.6096)
			(layers "F.Cu" "F.Mask" "F.Paste")
			(net "NC_PV09_RETIMER_CPU0_DNC1")
		)
		(pad "32" smd rect
			(at 1.160018 -2.899918)
			(size 0.2286 0.6096)
			(layers "F.Cu" "F.Mask" "F.Paste")
			(net "SW_P0V9_RETIMER_CPU0_PH1")
		)
		(pad "33" smd rect
			(at 0.70993 -2.899918)
			(size 0.2286 0.6096)
			(layers "F.Cu" "F.Mask" "F.Paste")
			(net "SW_P0V9_RETIMER_CPU0_BOOT1")
		)
		(pad "34" smd rect
			(at 0.260096 -2.899918)
			(size 0.2286 0.6096)
			(layers "F.Cu" "F.Mask" "F.Paste")
			(net "P0V9_RETIMER_CPU0_PWM1")
		)
		(pad "35" smd rect
			(at -0.189992 -2.899918)
			(size 0.2286 0.6096)
			(layers "F.Cu" "F.Mask" "F.Paste")
			(net "P0V9_RETIMER_CPU0_VCC1")
		)
		(pad "36" smd rect
			(at -0.64008 -2.899918)
			(size 0.2286 0.6096)
			(layers "F.Cu" "F.Mask" "F.Paste")
			(net "P0V9_RETIMER_CPU0_TEMP0")
		)
		(pad "37" smd rect
			(at -1.089914 -2.899918)
			(size 0.2286 0.6096)
			(layers "F.Cu" "F.Mask" "F.Paste")
			(net "P0V9_RETIMER_CPU0_LSET1")
		)
		(pad "38" smd rect
			(at -1.540002 -2.899918)
			(size 0.2286 0.6096)
			(layers "F.Cu" "F.Mask" "F.Paste")
			(net "P0V9_RETIMER_CPU0_IMON1")
		)
		(pad "39" smd rect
			(at -1.99009 -2.899918)
			(size 0.2286 0.6096)
			(layers "F.Cu" "F.Mask" "F.Paste")
			(net "PV09_RETIMER_CPU0_VCCS")
		)
		(pad "40" smd rect
			(at -0.87503 -1.27508)
			(size 1.7526 1.9558)
			(layers "F.Cu" "F.Mask" "F.Paste")
			(net "GND")
		)
		(pad "41" smd rect
			(at -1.525016 0.249936 270)
			(size 0.3048 0.4572)
			(layers "F.Cu" "F.Mask" "F.Paste")
			(net "NC_PV09_RETIMER_CPU0_GL2_1")
		)
		(zone
			(layer "F.Cu")
			(hatch none 0.5)
			(connect_pads
				(clearance 0)
			)
			(min_thickness 0.25)
			(keepout
				(tracks not_allowed)
				(vias allowed)
				(pads allowed)
				(copperpour not_allowed)
				(footprints allowed)
			)
			(placement
				(enabled no)
				(sheetname "")
			)
			(fill
				(thermal_gap 0.5)
				(thermal_bridge_width 0.5)
				(island_removal_mode 0)
			)
			(polygon
				(pts
					(xy 442.63183 -394.245338) (xy 442.63183 -394.994638) (xy 447.632074 -394.994638) (xy 447.632074 -394.245338)
					(xy 447.341752 -394.245338) (xy 447.341752 -394.701014) (xy 442.922152 -394.701014) (xy 442.922152 -394.245338)
				)
			)
		)
		(zone
			(layer "F.Cu")
			(hatch none 0.5)
			(connect_pads
				(clearance 0)
			)
			(min_thickness 0.25)
			(keepout
				(tracks not_allowed)
				(vias allowed)
				(pads allowed)
				(copperpour not_allowed)
				(footprints allowed)
			)
			(placement
				(enabled no)
				(sheetname "")
			)
			(fill
				(thermal_gap 0.5)
				(thermal_bridge_width 0.5)
				(island_removal_mode 0)
			)
			(polygon
				(pts
					(xy 442.63183 -396.496032) (xy 442.63183 -396.952724) (xy 443.327536 -396.952724) (xy 443.327536 -396.792196)
					(xy 443.886336 -396.792196) (xy 443.886336 -397.198596) (xy 443.327536 -397.198596) (xy 443.327536 -396.978124)
					(xy 442.63183 -396.978124) (xy 442.63183 -397.105124) (xy 443.087506 -397.105124) (xy 443.087506 -399.282666)
					(xy 443.329822 -399.282666) (xy 443.329822 -397.491712) (xy 445.184022 -397.491712) (xy 445.184022 -399.549112)
					(xy 443.329822 -399.549112) (xy 443.329822 -399.308066) (xy 443.087506 -399.308066) (xy 443.087506 -399.78965)
					(xy 447.632074 -399.78965) (xy 447.632074 -399.604738) (xy 445.47536 -399.604738) (xy 445.47536 -397.445738)
					(xy 447.632074 -397.445738) (xy 447.632074 -397.196056) (xy 444.18123 -397.196056) (xy 444.18123 -396.496032)
				)
			)
		)
	)
	(footprint ""
		(layer "F.Cu")
		(at 319.084706 -416.899344 -90)
		(property "Reference" "C6512"
			(at 0 0 270)
			(layer "F.SilkS")
			(hide yes)
			(effects
				(font
					(size 1.27 1.27)
				)
			)
		)
		(property "Value" ""
			(at 0 0 270)
			(layer "F.Fab")
			(effects
				(font
					(size 1.27 1.27)
				)
			)
		)
		(duplicate_pad_numbers_are_jumpers no)
		(fp_line
			(start -0.299974 0.150114)
			(end -0.299974 -0.150114)
			(stroke
				(width 0.1)
				(type default)
			)
			(layer "F.Fab")
		)
		(fp_line
			(start 0.299974 0.150114)
			(end -0.299974 0.150114)
			(stroke
				(width 0.1)
				(type default)
			)
			(layer "F.Fab")
		)
		(fp_line
			(start -0.299974 -0.150114)
			(end 0.299974 -0.150114)
			(stroke
				(width 0.1)
				(type default)
			)
			(layer "F.Fab")
		)
		(fp_line
			(start 0.299974 -0.150114)
			(end 0.299974 0.150114)
			(stroke
				(width 0.1)
				(type default)
			)
			(layer "F.Fab")
		)
		(pad "1" smd rect
			(at -0.2667 0 270)
			(size 0.3048 0.381)
			(layers "F.Cu" "F.Mask" "F.Paste")
			(net "P5E_CPU0_P0_TX_BUF_C_DN<5>")
		)
		(pad "2" smd rect
			(at 0.2667 0 270)
			(size 0.3048 0.381)
			(layers "F.Cu" "F.Mask" "F.Paste")
			(net "P5E_CPU0_P0_TX_BUF_DN<5>")
		)
	)
	(footprint ""
		(layer "F.Cu")
		(at 161.571686 -58.66765 180)
		(property "Reference" "R3574"
			(at 0 0 180)
			(layer "F.SilkS")
			(hide yes)
			(effects
				(font
					(size 1.27 1.27)
				)
			)
		)
		(property "Value" ""
			(at 0 0 180)
			(layer "F.Fab")
			(effects
				(font
					(size 1.27 1.27)
				)
			)
		)
		(duplicate_pad_numbers_are_jumpers no)
		(fp_line
			(start 0.7874 0.4064)
			(end -0.7874 0.4064)
			(stroke
				(width 0.1524)
				(type default)
			)
			(layer "F.SilkS")
		)
		(fp_line
			(start 0.7874 -0.4064)
			(end 0.7874 0.4064)
			(stroke
				(width 0.1524)
				(type default)
			)
			(layer "F.SilkS")
		)
		(fp_line
			(start -0.7874 0.4064)
			(end -0.7874 -0.4064)
			(stroke
				(width 0.1524)
				(type default)
			)
			(layer "F.SilkS")
		)
		(fp_line
			(start -0.7874 -0.4064)
			(end 0.7874 -0.4064)
			(stroke
				(width 0.1524)
				(type default)
			)
			(layer "F.SilkS")
		)
		(fp_line
			(start 0.67945 0.3048)
			(end 0.120396 0.3048)
			(stroke
				(width 0.1)
				(type default)
			)
			(layer "F.Fab")
		)
		(fp_line
			(start 0.67945 -0.3048)
			(end 0.67945 0.3048)
			(stroke
				(width 0.1)
				(type default)
			)
			(layer "F.Fab")
		)
		(fp_line
			(start 0.12065 -0.2794)
			(end 0.12065 -0.3048)
			(stroke
				(width 0.1)
				(type default)
			)
			(layer "F.Fab")
		)
		(fp_line
			(start 0.12065 -0.3048)
			(end 0.67945 -0.3048)
			(stroke
				(width 0.1)
				(type default)
			)
			(layer "F.Fab")
		)
		(fp_line
			(start 0.120396 0.3048)
			(end 0.120396 0.2794)
			(stroke
				(width 0.1)
				(type default)
			)
			(layer "F.Fab")
		)
		(fp_line
			(start 0.120396 0.2794)
			(end -0.12065 0.2794)
			(stroke
				(width 0.1)
				(type default)
			)
			(layer "F.Fab")
		)
		(fp_line
			(start -0.12065 0.3048)
			(end -0.67945 0.3048)
			(stroke
				(width 0.1)
				(type default)
			)
			(layer "F.Fab")
		)
		(fp_line
			(start -0.12065 0.2794)
			(end -0.12065 0.3048)
			(stroke
				(width 0.1)
				(type default)
			)
			(layer "F.Fab")
		)
		(fp_line
			(start -0.12065 -0.2794)
			(end 0.12065 -0.2794)
			(stroke
				(width 0.1)
				(type default)
			)
			(layer "F.Fab")
		)
		(fp_line
			(start -0.12065 -0.305054)
			(end -0.12065 -0.2794)
			(stroke
				(width 0.1)
				(type default)
			)
			(layer "F.Fab")
		)
		(fp_line
			(start -0.67945 0.3048)
			(end -0.67945 -0.305054)
			(stroke
				(width 0.1)
				(type default)
			)
			(layer "F.Fab")
		)
		(fp_line
			(start -0.67945 -0.305054)
			(end -0.12065 -0.305054)
			(stroke
				(width 0.1)
				(type default)
			)
			(layer "F.Fab")
		)
		(pad "1" smd circle
			(at -0.40005 0 180)
			(size 0 0)
			(layers "F.Cu" "F.Mask" "F.Paste")
			(net "P3V3")
		)
		(pad "2" smd circle
			(at 0.40005 0 180)
			(size 0 0)
			(layers "F.Cu" "F.Mask" "F.Paste")
			(net "VSENSE_P12V_INA230_4_INP")
		)
	)
)
